(kicad_pcb
	(version 20260206)
	(generator "pcbnew")
	(generator_version "10.0")
	(general
		(thickness 1.6)
		(legacy_teardrops no)
	)
	(paper "A4")
	(title_block
		(title "Bryce Canyon_F.DPB_16315-1-OCP.brd")
		(comment 1 "Bryce Canyon / footprints 1033-1038 of 2223")
	)
	(layers
		(0 "F.Cu" signal "TOP")
		(4 "In1.Cu" signal "L2GND")
		(6 "In2.Cu" signal "L3")
		(8 "In3.Cu" signal "L4GND")
		(10 "In4.Cu" signal "L5")
		(12 "In5.Cu" signal "L6VCC")
		(14 "In6.Cu" signal "L7VCC")
		(16 "In7.Cu" signal "L8")
		(18 "In8.Cu" signal "L9GND")
		(20 "In9.Cu" signal "L10")
		(22 "In10.Cu" signal "L11GND")
		(2 "B.Cu" signal "BOTTOM")
		(9 "F.Adhes" user "F.Adhesive")
		(11 "B.Adhes" user "B.Adhesive")
		(13 "F.Paste" user "Package Geometry/Pastemask Top")
		(15 "B.Paste" user "Package Geometry/Pastemask Bottom")
		(5 "F.SilkS" user "Ref Des/Silkscreen Top")
		(7 "B.SilkS" user "Ref Des/Silkscreen Bottom")
		(1 "F.Mask" user "Board Geometry/Soldermask Top")
		(3 "B.Mask" user "Board Geometry/Soldermask Bottom")
		(17 "Dwgs.User" user "User.Drawings")
		(19 "Cmts.User" user "User.Comments")
		(21 "Eco1.User" user "User.Eco1")
		(23 "Eco2.User" user "User.Eco2")
		(25 "Edge.Cuts" user "Board Geometry/Outline")
		(27 "Margin" user)
		(31 "F.CrtYd" user "Package Geometry/Place Bound Top")
		(29 "B.CrtYd" user "Package Geometry/Place Bound Bottom")
		(35 "F.Fab" user "Ref Des/Assembly Top")
		(33 "B.Fab" user "Ref Des/Assembly Bottom")
	)
	(footprint ""
		(layer "F.Cu")
		(at 403.48535 -277.843742 90)
		(property "Reference" "R330"
			(at 0 0 90)
			(layer "F.SilkS")
			(hide yes)
			(effects
				(font
					(size 1.27 1.27)
				)
			)
		)
		(property "Value" "200KR2F-L-GP"
			(at 0.064008 -3.993896 90)
			(unlocked yes)
			(layer "F.Fab")
			(hide yes)
			(effects
				(font
					(size 1.016 1.016)
					(thickness 0.1524)
				)
			)
		)
		(property "Device Type" "R402H16"
			(at 0.064008 -5.517896 90)
			(unlocked yes)
			(layer "F.Fab")
			(hide yes)
			(effects
				(font
					(size 1.016 1.016)
					(thickness 0.1524)
				)
			)
		)
		(duplicate_pad_numbers_are_jumpers no)
		(fp_line
			(start 0.508 -0.9398)
			(end -0.508 -0.9398)
			(stroke
				(width 0.1524)
				(type default)
			)
			(layer "F.SilkS")
		)
		(fp_line
			(start -0.508 -0.9398)
			(end -0.508 0.9398)
			(stroke
				(width 0.1524)
				(type default)
			)
			(layer "F.SilkS")
		)
		(fp_rect
			(start -0.508 0.9398)
			(end 0.508 -0.9398)
			(stroke
				(width 0)
				(type default)
			)
			(fill no)
			(layer "F.CrtYd")
		)
		(fp_rect
			(start -0.508 0.9398)
			(end 0.508 -0.9398)
			(stroke
				(width 0)
				(type default)
			)
			(fill no)
			(layer "F.Fab")
		)
		(pad "1" smd custom
			(at 0 -0.4445 90)
			(size 0.1397 0.1397)
			(layers "F.Cu" "F.Mask" "F.Paste")
			(net "SW_HDD_R8")
			(options
				(clearance outline)
				(anchor circle)
			)
			(primitives
				(gr_poly
					(pts
						(arc
							(start -0.1778 -0.2794)
							(mid -0.249642 -0.249642)
							(end -0.2794 -0.1778)
						)
						(arc
							(start -0.2794 0.1778)
							(mid -0.249642 0.249642)
							(end -0.1778 0.2794)
						)
						(arc
							(start 0.1778 0.2794)
							(mid 0.249642 0.249642)
							(end 0.2794 0.1778)
						)
						(arc
							(start 0.2794 -0.1778)
							(mid 0.249642 -0.249642)
							(end 0.1778 -0.2794)
						)
					)
					(width 0)
					(fill yes)
				)
			)
		)
		(pad "2" smd custom
			(at 0 0.4445 90)
			(size 0.1397 0.1397)
			(layers "F.Cu" "F.Mask" "F.Paste")
			(net "SW_HDD_N8")
			(options
				(clearance outline)
				(anchor circle)
			)
			(primitives
				(gr_poly
					(pts
						(arc
							(start -0.1778 -0.2794)
							(mid -0.249642 -0.249642)
							(end -0.2794 -0.1778)
						)
						(arc
							(start -0.2794 0.1778)
							(mid -0.249642 0.249642)
							(end -0.1778 0.2794)
						)
						(arc
							(start 0.1778 0.2794)
							(mid 0.249642 0.249642)
							(end 0.2794 0.1778)
						)
						(arc
							(start 0.2794 -0.1778)
							(mid 0.249642 -0.249642)
							(end 0.1778 -0.2794)
						)
					)
					(width 0)
					(fill yes)
				)
			)
		)
	)
	(footprint ""
		(layer "F.Cu")
		(at 248.466102 -393.538964 -90)
		(property "Reference" "R1168"
			(at 0 0 270)
			(layer "F.SilkS")
			(hide yes)
			(effects
				(font
					(size 1.27 1.27)
				)
			)
		)
		(property "Value" "49K9R2F-L-GP"
			(at 0.064008 -3.993896 270)
			(unlocked yes)
			(layer "F.Fab")
			(hide yes)
			(effects
				(font
					(size 1.016 1.016)
					(thickness 0.1524)
				)
			)
		)
		(property "Device Type" "R402H16"
			(at 0.064008 -5.517896 270)
			(unlocked yes)
			(layer "F.Fab")
			(hide yes)
			(effects
				(font
					(size 1.016 1.016)
					(thickness 0.1524)
				)
			)
		)
		(duplicate_pad_numbers_are_jumpers no)
		(fp_line
			(start -0.508 -0.9398)
			(end -0.508 0.9398)
			(stroke
				(width 0.1524)
				(type default)
			)
			(layer "F.SilkS")
		)
		(fp_line
			(start 0.508 -0.9398)
			(end -0.508 -0.9398)
			(stroke
				(width 0.1524)
				(type default)
			)
			(layer "F.SilkS")
		)
		(fp_rect
			(start -0.508 0.9398)
			(end 0.508 -0.9398)
			(stroke
				(width 0)
				(type default)
			)
			(fill no)
			(layer "F.CrtYd")
		)
		(fp_rect
			(start -0.508 0.9398)
			(end 0.508 -0.9398)
			(stroke
				(width 0)
				(type default)
			)
			(fill no)
			(layer "F.Fab")
		)
		(pad "1" smd custom
			(at 0 -0.4445 270)
			(size 0.1397 0.1397)
			(layers "F.Cu" "F.Mask" "F.Paste")
			(net "P12V_IN")
			(options
				(clearance outline)
				(anchor circle)
			)
			(primitives
				(gr_poly
					(pts
						(arc
							(start -0.1778 -0.2794)
							(mid -0.249642 -0.249642)
							(end -0.2794 -0.1778)
						)
						(arc
							(start -0.2794 0.1778)
							(mid -0.249642 0.249642)
							(end -0.1778 0.2794)
						)
						(arc
							(start 0.1778 0.2794)
							(mid 0.249642 0.249642)
							(end 0.2794 0.1778)
						)
						(arc
							(start 0.2794 -0.1778)
							(mid 0.249642 -0.249642)
							(end 0.1778 -0.2794)
						)
					)
					(width 0)
					(fill yes)
				)
			)
		)
		(pad "2" smd custom
			(at 0 0.4445 270)
			(size 0.1397 0.1397)
			(layers "F.Cu" "F.Mask" "F.Paste")
			(net "MB3_CM_UV_R")
			(options
				(clearance outline)
				(anchor circle)
			)
			(primitives
				(gr_poly
					(pts
						(arc
							(start -0.1778 -0.2794)
							(mid -0.249642 -0.249642)
							(end -0.2794 -0.1778)
						)
						(arc
							(start -0.2794 0.1778)
							(mid -0.249642 0.249642)
							(end -0.1778 0.2794)
						)
						(arc
							(start 0.1778 0.2794)
							(mid 0.249642 0.249642)
							(end 0.2794 0.1778)
						)
						(arc
							(start 0.2794 -0.1778)
							(mid 0.249642 -0.249642)
							(end 0.1778 -0.2794)
						)
					)
					(width 0)
					(fill yes)
				)
			)
		)
	)
	(footprint ""
		(layer "F.Cu")
		(at 262.308848 17.959832 90)
		(property "Reference" "C47"
			(at 0 0 90)
			(layer "F.SilkS")
			(hide yes)
			(effects
				(font
					(size 1.27 1.27)
				)
			)
		)
		(property "Value" "SCD1U16V2KX-3GP"
			(at 1.1811 -2.7051 90)
			(unlocked yes)
			(layer "F.Fab")
			(hide yes)
			(effects
				(font
					(size 1.016 1.016)
					(thickness 0.1524)
				)
			)
		)
		(property "Device Type" "C402H22"
			(at 1.1811 -4.2291 90)
			(unlocked yes)
			(layer "F.Fab")
			(hide yes)
			(effects
				(font
					(size 1.016 1.016)
					(thickness 0.1524)
				)
			)
		)
		(duplicate_pad_numbers_are_jumpers no)
		(fp_rect
			(start -0.4318 0.9525)
			(end 0.4318 -0.9525)
			(stroke
				(width 0)
				(type default)
			)
			(fill no)
			(layer "F.CrtYd")
		)
		(fp_rect
			(start -0.4318 0.9525)
			(end 0.4318 -0.9525)
			(stroke
				(width 0)
				(type default)
			)
			(fill no)
			(layer "F.Fab")
		)
		(pad "1" smd custom
			(at 0 -0.4445 90)
			(size 0.1524 0.1524)
			(layers "F.Cu" "F.Mask" "F.Paste")
			(net "P5V_USB_A")
			(options
				(clearance outline)
				(anchor circle)
			)
			(primitives
				(gr_poly
					(pts
						(arc
							(start 0.3048 -0.2032)
							(mid 0.275042 -0.275042)
							(end 0.2032 -0.3048)
						)
						(arc
							(start -0.2032 -0.3048)
							(mid -0.275042 -0.275042)
							(end -0.3048 -0.2032)
						)
						(arc
							(start -0.3048 0.2032)
							(mid -0.275042 0.275042)
							(end -0.2032 0.3048)
						)
						(arc
							(start 0.2032 0.3048)
							(mid 0.275042 0.275042)
							(end 0.3048 0.2032)
						)
					)
					(width 0)
					(fill yes)
				)
			)
		)
		(pad "2" smd custom
			(at 0 0.4445 90)
			(size 0.1524 0.1524)
			(layers "F.Cu" "F.Mask" "F.Paste")
			(net "GND")
			(options
				(clearance outline)
				(anchor circle)
			)
			(primitives
				(gr_poly
					(pts
						(arc
							(start 0.3048 -0.2032)
							(mid 0.275042 -0.275042)
							(end 0.2032 -0.3048)
						)
						(arc
							(start -0.2032 -0.3048)
							(mid -0.275042 -0.275042)
							(end -0.3048 -0.2032)
						)
						(arc
							(start -0.3048 0.2032)
							(mid -0.275042 0.275042)
							(end -0.2032 0.3048)
						)
						(arc
							(start 0.2032 0.3048)
							(mid 0.275042 0.275042)
							(end 0.3048 0.2032)
						)
					)
					(width 0)
					(fill yes)
				)
			)
		)
	)
	(footprint ""
		(layer "F.Cu")
		(at 112.450118 -324.39991)
		(property "Reference" "RLED28"
			(at 0 0 0)
			(layer "F.SilkS")
			(hide yes)
			(effects
				(font
					(size 1.27 1.27)
				)
			)
		)
		(property "Value" "LED-BY-19-GP"
			(at -2.132076 1.414018 0)
			(unlocked yes)
			(layer "F.Fab")
			(hide yes)
			(effects
				(font
					(size 1.016 1.016)
					(thickness 0.1524)
				)
			)
		)
		(property "Device Type" "LED-1615-4PH26"
			(at -2.132076 -0.109982 0)
			(unlocked yes)
			(layer "F.Fab")
			(hide yes)
			(effects
				(font
					(size 1.016 1.016)
					(thickness 0.1524)
				)
			)
		)
		(duplicate_pad_numbers_are_jumpers no)
		(fp_line
			(start -1.2954 0.254)
			(end -1.2954 1.6002)
			(stroke
				(width 0.508)
				(type default)
			)
			(layer "F.SilkS")
		)
		(fp_line
			(start -1.2954 1.6002)
			(end 1.2954 1.6002)
			(stroke
				(width 0.508)
				(type default)
			)
			(layer "F.SilkS")
		)
		(fp_line
			(start -1.1176 -1.4224)
			(end 1.1176 -1.4224)
			(stroke
				(width 0.1524)
				(type default)
			)
			(layer "F.SilkS")
		)
		(fp_line
			(start -1.1176 1.4224)
			(end -1.1176 -1.4224)
			(stroke
				(width 0.1524)
				(type default)
			)
			(layer "F.SilkS")
		)
		(fp_line
			(start 1.1176 -1.4224)
			(end 1.1176 1.4224)
			(stroke
				(width 0.1524)
				(type default)
			)
			(layer "F.SilkS")
		)
		(fp_line
			(start 1.1176 1.4224)
			(end -1.1176 1.4224)
			(stroke
				(width 0.1524)
				(type default)
			)
			(layer "F.SilkS")
		)
		(fp_line
			(start 1.2954 1.6002)
			(end 1.2954 0.254)
			(stroke
				(width 0.508)
				(type default)
			)
			(layer "F.SilkS")
		)
		(fp_rect
			(start -0.7493 0.8001)
			(end 0.7493 -0.8001)
			(stroke
				(width 0)
				(type default)
			)
			(fill no)
			(layer "F.CrtYd")
		)
		(fp_poly
			(pts
				(xy -1.3716 1.6764) (xy -1.3716 -1.6764) (xy 1.3716 -1.6764) (xy 1.3716 0.0635) (xy 0.7493 0.0635)
				(xy 0.7493 -0.8001) (xy -0.7493 -0.8001) (xy -0.7493 0.8001) (xy 0.7493 0.8001) (xy 0.7493 0.0762)
				(xy 1.3716 0.0762) (xy 1.3716 1.6764)
			)
			(stroke
				(width 0)
				(type default)
			)
			(fill no)
			(layer "F.CrtYd")
		)
		(fp_rect
			(start -1.3716 1.6764)
			(end 1.3716 -1.6764)
			(stroke
				(width 0)
				(type default)
			)
			(fill no)
			(layer "F.Fab")
		)
		(pad "1" smd rect
			(at 0.50038 -0.73025)
			(size 0.7112 0.8636)
			(layers "F.Cu" "F.Mask" "F.Paste")
			(net "DRV_ACT_27")
		)
		(pad "2" smd rect
			(at -0.50038 -0.73025)
			(size 0.7112 0.8636)
			(layers "F.Cu" "F.Mask" "F.Paste")
			(net "FLT_HDD27")
		)
		(pad "3" smd rect
			(at 0.50038 0.73025)
			(size 0.7112 0.8636)
			(layers "F.Cu" "F.Mask" "F.Paste")
			(net "DRV_ACT_27_N")
		)
		(pad "4" smd rect
			(at -0.50038 0.73025)
			(size 0.7112 0.8636)
			(layers "F.Cu" "F.Mask" "F.Paste")
			(net "FLT_HDD27_N")
		)
	)
	(footprint ""
		(layer "F.Cu")
		(at 381.38735 -61.102494 -90)
		(property "Reference" "C458"
			(at 0 0 270)
			(layer "F.SilkS")
			(hide yes)
			(effects
				(font
					(size 1.27 1.27)
				)
			)
		)
		(property "Value" "SCD01U50V2KX-1GP"
			(at 1.1811 -2.7051 270)
			(unlocked yes)
			(layer "F.Fab")
			(hide yes)
			(effects
				(font
					(size 1.016 1.016)
					(thickness 0.1524)
				)
			)
		)
		(property "Device Type" "C402H22"
			(at 1.1811 -4.2291 270)
			(unlocked yes)
			(layer "F.Fab")
			(hide yes)
			(effects
				(font
					(size 1.016 1.016)
					(thickness 0.1524)
				)
			)
		)
		(duplicate_pad_numbers_are_jumpers no)
		(fp_rect
			(start -0.4318 0.9525)
			(end 0.4318 -0.9525)
			(stroke
				(width 0)
				(type default)
			)
			(fill no)
			(layer "F.CrtYd")
		)
		(fp_rect
			(start -0.4318 0.9525)
			(end 0.4318 -0.9525)
			(stroke
				(width 0)
				(type default)
			)
			(fill no)
			(layer "F.Fab")
		)
		(pad "1" smd custom
			(at 0 -0.4445 270)
			(size 0.1524 0.1524)
			(layers "F.Cu" "F.Mask" "F.Paste")
			(net "HDD_PRSNT_32")
			(options
				(clearance outline)
				(anchor circle)
			)
			(primitives
				(gr_poly
					(pts
						(arc
							(start 0.3048 -0.2032)
							(mid 0.275042 -0.275042)
							(end 0.2032 -0.3048)
						)
						(arc
							(start -0.2032 -0.3048)
							(mid -0.275042 -0.275042)
							(end -0.3048 -0.2032)
						)
						(arc
							(start -0.3048 0.2032)
							(mid -0.275042 0.275042)
							(end -0.2032 0.3048)
						)
						(arc
							(start 0.2032 0.3048)
							(mid 0.275042 0.275042)
							(end 0.3048 0.2032)
						)
					)
					(width 0)
					(fill yes)
				)
			)
		)
		(pad "2" smd custom
			(at 0 0.4445 270)
			(size 0.1524 0.1524)
			(layers "F.Cu" "F.Mask" "F.Paste")
			(net "GND")
			(options
				(clearance outline)
				(anchor circle)
			)
			(primitives
				(gr_poly
					(pts
						(arc
							(start 0.3048 -0.2032)
							(mid 0.275042 -0.275042)
							(end 0.2032 -0.3048)
						)
						(arc
							(start -0.2032 -0.3048)
							(mid -0.275042 -0.275042)
							(end -0.3048 -0.2032)
						)
						(arc
							(start -0.3048 0.2032)
							(mid -0.275042 0.275042)
							(end -0.2032 0.3048)
						)
						(arc
							(start 0.2032 0.3048)
							(mid 0.275042 0.275042)
							(end 0.3048 0.2032)
						)
					)
					(width 0)
					(fill yes)
				)
			)
		)
	)
	(footprint ""
		(layer "F.Cu")
		(at 35.667188 -304.428398 180)
		(property "Reference" "R209"
			(at 0 0 180)
			(layer "F.SilkS")
			(hide yes)
			(effects
				(font
					(size 1.27 1.27)
				)
			)
		)
		(property "Value" "130R3F-GP"
			(at -0.0254 -2.5146 180)
			(unlocked yes)
			(layer "F.Fab")
			(hide yes)
			(effects
				(font
					(size 1.016 1.016)
					(thickness 0.1524)
				)
			)
		)
		(property "Device Type" "R603H22"
			(at -0.0254 -4.0386 180)
			(unlocked yes)
			(layer "F.Fab")
			(hide yes)
			(effects
				(font
					(size 1.016 1.016)
					(thickness 0.1524)
				)
			)
		)
		(duplicate_pad_numbers_are_jumpers no)
		(fp_line
			(start 0.2032 0)
			(end 0.4826 0)
			(stroke
				(width 0.2032)
				(type default)
			)
			(layer "F.SilkS")
		)
		(fp_line
			(start -0.4826 0)
			(end -0.2032 0)
			(stroke
				(width 0.2032)
				(type default)
			)
			(layer "F.SilkS")
		)
		(fp_rect
			(start -0.5842 1.3335)
			(end 0.5842 -1.3335)
			(stroke
				(width 0)
				(type default)
			)
			(fill no)
			(layer "F.CrtYd")
		)
		(fp_rect
			(start -0.5842 1.3335)
			(end 0.5842 -1.3335)
			(stroke
				(width 0)
				(type default)
			)
			(fill no)
			(layer "F.Fab")
		)
		(pad "1" smd custom
			(at 0 -0.762 180)
			(size 0.2159 0.2159)
			(layers "F.Cu" "F.Mask" "F.Paste")
			(net "P5V_B")
			(options
				(clearance outline)
				(anchor circle)
			)
			(primitives
				(gr_poly
					(pts
						(arc
							(start -0.3302 -0.4318)
							(mid -0.402042 -0.402042)
							(end -0.4318 -0.3302)
						)
						(arc
							(start -0.4318 0.3302)
							(mid -0.402042 0.402042)
							(end -0.3302 0.4318)
						)
						(arc
							(start 0.3302 0.4318)
							(mid 0.402042 0.402042)
							(end 0.4318 0.3302)
						)
						(arc
							(start 0.4318 -0.3302)
							(mid 0.402042 -0.402042)
							(end 0.3302 -0.4318)
						)
					)
					(width 0)
					(fill yes)
				)
			)
		)
		(pad "2" smd custom
			(at 0 0.762 180)
			(size 0.2159 0.2159)
			(layers "F.Cu" "F.Mask" "F.Paste")
			(net "FLT_HDD25")
			(options
				(clearance outline)
				(anchor circle)
			)
			(primitives
				(gr_poly
					(pts
						(arc
							(start -0.3302 -0.4318)
							(mid -0.402042 -0.402042)
							(end -0.4318 -0.3302)
						)
						(arc
							(start -0.4318 0.3302)
							(mid -0.402042 0.402042)
							(end -0.3302 0.4318)
						)
						(arc
							(start 0.3302 0.4318)
							(mid 0.402042 0.402042)
							(end 0.4318 0.3302)
						)
						(arc
							(start 0.4318 -0.3302)
							(mid 0.402042 -0.402042)
							(end 0.3302 -0.4318)
						)
					)
					(width 0)
					(fill yes)
				)
			)
		)
	)
)
